(kicad_pcb
	(version 20260206)
	(generator "pcbnew")
	(generator_version "10.0")
	(general
		(thickness 1.6)
		(legacy_teardrops no)
	)
	(paper "A4")
	(title_block
		(title "04192023_DAF0TMB3IC0_F0TG_MB_C_brd_V02_OCP.brd")
		(comment 1 "Grand Teton / footprint 2783 of 8354 (U26), pads 1763-1877 of 6102")
	)
	(layers
		(0 "F.Cu" signal "TOP")
		(4 "In1.Cu" signal "GND")
		(6 "In2.Cu" signal "IN1")
		(8 "In3.Cu" signal "GND1")
		(10 "In4.Cu" signal "IN2")
		(12 "In5.Cu" signal "GND2")
		(14 "In6.Cu" signal "IN3")
		(16 "In7.Cu" signal "GND3")
		(18 "In8.Cu" signal "VCC")
		(20 "In9.Cu" signal "VCC1")
		(22 "In10.Cu" signal "GND4")
		(24 "In11.Cu" signal "IN4")
		(26 "In12.Cu" signal "GND5")
		(28 "In13.Cu" signal "IN5")
		(30 "In14.Cu" signal "GND6")
		(32 "In15.Cu" signal "IN6")
		(34 "In16.Cu" signal "GND7")
		(2 "B.Cu" signal "BOTTOM")
		(9 "F.Adhes" user "F.Adhesive")
		(11 "B.Adhes" user "B.Adhesive")
		(13 "F.Paste" user "Package Geometry/Pastemask Top")
		(15 "B.Paste" user "Package Geometry/Pastemask Bottom")
		(5 "F.SilkS" user "Ref Des/Silkscreen Top")
		(7 "B.SilkS" user "Ref Des/Silkscreen Bottom")
		(1 "F.Mask" user "Board Geometry/Soldermask Top")
		(3 "B.Mask" user "Board Geometry/Soldermask Bottom")
		(17 "Dwgs.User" user "User.Drawings")
		(19 "Cmts.User" user "User.Comments")
		(21 "Eco1.User" user "User.Eco1")
		(23 "Eco2.User" user "User.Eco2")
		(25 "Edge.Cuts" user "Board Geometry/Outline")
		(27 "Margin" user)
		(31 "F.CrtYd" user "Package Geometry/Place Bound Top")
		(29 "B.CrtYd" user "Package Geometry/Place Bound Bottom")
		(35 "F.Fab" user "Ref Des/Assembly Top")
		(33 "B.Fab" user "Ref Des/Assembly Bottom")
	)
	(footprint ""
		(layer "F.Cu")
		(at 111.927894 -258.880356 180)
		(property "Reference" "U26"
			(at -45.05579 -61.794136 0)
			(unlocked yes)
			(layer "F.SilkS")
			(effects
				(font
					(size 0.7874 0.5842)
					(thickness 0.1524)
				)
			)
		)
		(property "Value" ""
			(at 0 0 180)
			(layer "F.Fab")
			(effects
				(font
					(size 1.27 1.27)
				)
			)
		)
		(duplicate_pad_numbers_are_jumpers no)
		(pad "BF6" smd circle
			(at -30.230064 1.97993 180)
			(size 0.450088 0.450088)
			(layers "F.Cu" "F.Mask" "F.Paste")
			(net "Net_2187")
		)
		(pad "BF7" smd circle
			(at -29.29001 1.97993 180)
			(size 0.450088 0.450088)
			(layers "F.Cu" "F.Mask" "F.Paste")
			(net "TP_M_K_CPU1_SA_TEST39K")
		)
		(pad "BF8" smd circle
			(at -28.349956 1.97993 180)
			(size 0.450088 0.450088)
			(layers "F.Cu" "F.Mask" "F.Paste")
			(net "GND")
		)
		(pad "BF9" smd circle
			(at -27.409902 1.97993 180)
			(size 0.450088 0.450088)
			(layers "F.Cu" "F.Mask" "F.Paste")
			(net "Net_2179")
		)
		(pad "BF10" smd circle
			(at -26.470102 1.97993 180)
			(size 0.450088 0.450088)
			(layers "F.Cu" "F.Mask" "F.Paste")
			(net "GND")
		)
		(pad "BF11" smd circle
			(at -25.530048 1.97993 180)
			(size 0.450088 0.450088)
			(layers "F.Cu" "F.Mask" "F.Paste")
			(net "TP_M_L_CPU1_SA_TEST39L")
		)
		(pad "BF12" smd circle
			(at -24.589994 1.97993 180)
			(size 0.450088 0.450088)
			(layers "F.Cu" "F.Mask" "F.Paste")
			(net "GND")
		)
		(pad "BF13" smd circle
			(at -23.64994 1.97993 180)
			(size 0.450088 0.450088)
			(layers "F.Cu" "F.Mask" "F.Paste")
			(net "Net_2046")
		)
		(pad "BF14" smd circle
			(at -22.709886 1.97993 180)
			(size 0.450088 0.450088)
			(layers "F.Cu" "F.Mask" "F.Paste")
			(net "TP_M_H_CPU1_SA_TEST39H")
		)
		(pad "BF15" smd circle
			(at -21.770086 1.97993 180)
			(size 0.450088 0.450088)
			(layers "F.Cu" "F.Mask" "F.Paste")
			(net "GND")
		)
		(pad "BF16" smd circle
			(at -20.830032 1.97993 180)
			(size 0.450088 0.450088)
			(layers "F.Cu" "F.Mask" "F.Paste")
			(net "Net_2062")
		)
		(pad "BF17" smd circle
			(at -19.889978 1.97993 180)
			(size 0.450088 0.450088)
			(layers "F.Cu" "F.Mask" "F.Paste")
			(net "GND")
		)
		(pad "BF18" smd circle
			(at -18.949924 1.97993 180)
			(size 0.450088 0.450088)
			(layers "F.Cu" "F.Mask" "F.Paste")
			(net "TP_M_J_CPU1_SA_TEST39J")
		)
		(pad "BF19" smd circle
			(at -18.010124 1.97993 180)
			(size 0.450088 0.450088)
			(layers "F.Cu" "F.Mask" "F.Paste")
			(net "GND")
		)
		(pad "BF20" smd circle
			(at -17.07007 1.97993 180)
			(size 0.450088 0.450088)
			(layers "F.Cu" "F.Mask" "F.Paste")
			(net "Net_2054")
		)
		(pad "BF21" smd circle
			(at -16.130016 1.97993 180)
			(size 0.450088 0.450088)
			(layers "F.Cu" "F.Mask" "F.Paste")
			(net "TP_M_I_CPU1_SA_TEST39I")
		)
		(pad "BF22" smd circle
			(at -15.189962 1.97993 180)
			(size 0.450088 0.450088)
			(layers "F.Cu" "F.Mask" "F.Paste")
			(net "GND")
		)
		(pad "BF23" smd circle
			(at -14.249908 1.97993 180)
			(size 0.450088 0.450088)
			(layers "F.Cu" "F.Mask" "F.Paste")
			(net "PVDDCR_SOC_P1")
		)
		(pad "BF24" smd circle
			(at -13.310108 1.97993 180)
			(size 0.450088 0.450088)
			(layers "F.Cu" "F.Mask" "F.Paste")
			(net "GND")
		)
		(pad "BF25" smd circle
			(at -12.370054 1.97993 180)
			(size 0.450088 0.450088)
			(layers "F.Cu" "F.Mask" "F.Paste")
			(net "PVDDCR_SOC_P1")
		)
		(pad "BF26" smd circle
			(at -11.43 1.97993 180)
			(size 0.450088 0.450088)
			(layers "F.Cu" "F.Mask" "F.Paste")
			(net "GND")
		)
		(pad "BF27" smd circle
			(at -10.489946 1.97993 180)
			(size 0.450088 0.450088)
			(layers "F.Cu" "F.Mask" "F.Paste")
			(net "PVDDCR_SOC_P1")
		)
		(pad "BF28" smd circle
			(at -9.549892 1.97993 180)
			(size 0.450088 0.450088)
			(layers "F.Cu" "F.Mask" "F.Paste")
			(net "GND")
		)
		(pad "BF48" smd circle
			(at 9.249918 1.97993 180)
			(size 0.450088 0.450088)
			(layers "F.Cu" "F.Mask" "F.Paste")
			(net "PVDDCR_SOC_P1")
		)
		(pad "BF49" smd circle
			(at 10.189972 1.97993 180)
			(size 0.450088 0.450088)
			(layers "F.Cu" "F.Mask" "F.Paste")
			(net "GND")
		)
		(pad "BF50" smd circle
			(at 11.130026 1.97993 180)
			(size 0.450088 0.450088)
			(layers "F.Cu" "F.Mask" "F.Paste")
			(net "GND")
		)
		(pad "BF51" smd circle
			(at 12.07008 1.97993 180)
			(size 0.450088 0.450088)
			(layers "F.Cu" "F.Mask" "F.Paste")
			(net "PVDDIO_P1")
		)
		(pad "BF52" smd circle
			(at 13.00988 1.97993 180)
			(size 0.450088 0.450088)
			(layers "F.Cu" "F.Mask" "F.Paste")
			(net "GND")
		)
		(pad "BF53" smd circle
			(at 13.949934 1.97993 180)
			(size 0.450088 0.450088)
			(layers "F.Cu" "F.Mask" "F.Paste")
			(net "PVDDIO_P1")
		)
		(pad "BF54" smd circle
			(at 14.889988 1.97993 180)
			(size 0.450088 0.450088)
			(layers "F.Cu" "F.Mask" "F.Paste")
			(net "GND")
		)
		(pad "BF55" smd circle
			(at 15.830042 1.97993 180)
			(size 0.450088 0.450088)
			(layers "F.Cu" "F.Mask" "F.Paste")
			(net "TP_M_C_CPU1_SA_TEST39C")
		)
		(pad "BF56" smd circle
			(at 16.770096 1.97993 180)
			(size 0.450088 0.450088)
			(layers "F.Cu" "F.Mask" "F.Paste")
			(net "Net_2006")
		)
		(pad "BF57" smd circle
			(at 17.709896 1.97993 180)
			(size 0.450088 0.450088)
			(layers "F.Cu" "F.Mask" "F.Paste")
			(net "PVDDIO_P1")
		)
		(pad "BF58" smd circle
			(at 18.64995 1.97993 180)
			(size 0.450088 0.450088)
			(layers "F.Cu" "F.Mask" "F.Paste")
			(net "TP_M_D_CPU1_SA_TEST39D")
		)
		(pad "BF59" smd circle
			(at 19.590004 1.97993 180)
			(size 0.450088 0.450088)
			(layers "F.Cu" "F.Mask" "F.Paste")
			(net "GND")
		)
		(pad "BF60" smd circle
			(at 20.530058 1.97993 180)
			(size 0.450088 0.450088)
			(layers "F.Cu" "F.Mask" "F.Paste")
			(net "Net_2014")
		)
		(pad "BF61" smd circle
			(at 21.470112 1.97993 180)
			(size 0.450088 0.450088)
			(layers "F.Cu" "F.Mask" "F.Paste")
			(net "GND")
		)
		(pad "BF62" smd circle
			(at 22.409912 1.97993 180)
			(size 0.450088 0.450088)
			(layers "F.Cu" "F.Mask" "F.Paste")
			(net "TP_M_B_CPU1_SA_TEST39B")
		)
		(pad "BF63" smd circle
			(at 23.349966 1.97993 180)
			(size 0.450088 0.450088)
			(layers "F.Cu" "F.Mask" "F.Paste")
			(net "Net_1998")
		)
		(pad "BF64" smd circle
			(at 24.29002 1.97993 180)
			(size 0.450088 0.450088)
			(layers "F.Cu" "F.Mask" "F.Paste")
			(net "PVDDIO_P1")
		)
		(pad "BF65" smd circle
			(at 25.230074 1.97993 180)
			(size 0.450088 0.450088)
			(layers "F.Cu" "F.Mask" "F.Paste")
			(net "TP_M_F_CPU1_SA_TEST39F")
		)
		(pad "BF66" smd circle
			(at 26.170128 1.97993 180)
			(size 0.450088 0.450088)
			(layers "F.Cu" "F.Mask" "F.Paste")
			(net "GND")
		)
		(pad "BF67" smd circle
			(at 27.109928 1.97993 180)
			(size 0.450088 0.450088)
			(layers "F.Cu" "F.Mask" "F.Paste")
			(net "Net_2030")
		)
		(pad "BF68" smd circle
			(at 28.049982 1.97993 180)
			(size 0.450088 0.450088)
			(layers "F.Cu" "F.Mask" "F.Paste")
			(net "GND")
		)
		(pad "BF69" smd circle
			(at 28.990036 1.97993 180)
			(size 0.450088 0.450088)
			(layers "F.Cu" "F.Mask" "F.Paste")
			(net "TP_M_E_CPU1_SA_TEST39E")
		)
		(pad "BF70" smd circle
			(at 29.93009 1.97993 180)
			(size 0.450088 0.450088)
			(layers "F.Cu" "F.Mask" "F.Paste")
			(net "Net_2022")
		)
		(pad "BF71" smd circle
			(at 30.86989 1.97993 180)
			(size 0.450088 0.450088)
			(layers "F.Cu" "F.Mask" "F.Paste")
			(net "PVDDIO_P1")
		)
		(pad "BF72" smd circle
			(at 31.809944 1.97993 180)
			(size 0.450088 0.450088)
			(layers "F.Cu" "F.Mask" "F.Paste")
			(net "TP_M_A_CPU1_SA_TEST39A")
		)
		(pad "BF73" smd circle
			(at 32.749998 1.97993 180)
			(size 0.450088 0.450088)
			(layers "F.Cu" "F.Mask" "F.Paste")
			(net "GND")
		)
		(pad "BF74" smd circle
			(at 33.690052 1.97993 180)
			(size 0.450088 0.450088)
			(layers "F.Cu" "F.Mask" "F.Paste")
			(net "Net_1990")
		)
		(pad "BG1" smd circle
			(at -34.459926 2.789936 180)
			(size 0.450088 0.450088)
			(layers "F.Cu" "F.Mask" "F.Paste")
			(net "GND")
		)
		(pad "BG2" smd circle
			(at -33.519872 2.789936 180)
			(size 0.450088 0.450088)
			(layers "F.Cu" "F.Mask" "F.Paste")
			(net "Net_2039")
		)
		(pad "BG3" smd circle
			(at -32.580072 2.789936 180)
			(size 0.450088 0.450088)
			(layers "F.Cu" "F.Mask" "F.Paste")
			(net "M_G_CPU1_SB_CA<0>")
		)
		(pad "BG4" smd circle
			(at -31.640018 2.789936 180)
			(size 0.450088 0.450088)
			(layers "F.Cu" "F.Mask" "F.Paste")
			(net "GND")
		)
		(pad "BG5" smd circle
			(at -30.699964 2.789936 180)
			(size 0.450088 0.450088)
			(layers "F.Cu" "F.Mask" "F.Paste")
			(net "Net_2188")
		)
		(pad "BG6" smd circle
			(at -29.75991 2.789936 180)
			(size 0.450088 0.450088)
			(layers "F.Cu" "F.Mask" "F.Paste")
			(net "GND")
		)
		(pad "BG7" smd circle
			(at -28.82011 2.789936 180)
			(size 0.450088 0.450088)
			(layers "F.Cu" "F.Mask" "F.Paste")
			(net "M_K_CPU1_SB_CA<0>")
		)
		(pad "BG8" smd circle
			(at -27.880056 2.789936 180)
			(size 0.450088 0.450088)
			(layers "F.Cu" "F.Mask" "F.Paste")
			(net "GND")
		)
		(pad "BG9" smd circle
			(at -26.940002 2.789936 180)
			(size 0.450088 0.450088)
			(layers "F.Cu" "F.Mask" "F.Paste")
			(net "Net_2180")
		)
		(pad "BG10" smd circle
			(at -25.999948 2.789936 180)
			(size 0.450088 0.450088)
			(layers "F.Cu" "F.Mask" "F.Paste")
			(net "M_L_CPU1_SB_CA<0>")
		)
		(pad "BG11" smd circle
			(at -25.059894 2.789936 180)
			(size 0.450088 0.450088)
			(layers "F.Cu" "F.Mask" "F.Paste")
			(net "GND")
		)
		(pad "BG12" smd circle
			(at -24.120094 2.789936 180)
			(size 0.450088 0.450088)
			(layers "F.Cu" "F.Mask" "F.Paste")
			(net "Net_2047")
		)
		(pad "BG13" smd circle
			(at -23.18004 2.789936 180)
			(size 0.450088 0.450088)
			(layers "F.Cu" "F.Mask" "F.Paste")
			(net "GND")
		)
		(pad "BG14" smd circle
			(at -22.239986 2.789936 180)
			(size 0.450088 0.450088)
			(layers "F.Cu" "F.Mask" "F.Paste")
			(net "M_H_CPU1_SB_CA<0>")
		)
		(pad "BG15" smd circle
			(at -21.299932 2.789936 180)
			(size 0.450088 0.450088)
			(layers "F.Cu" "F.Mask" "F.Paste")
			(net "GND")
		)
		(pad "BG16" smd circle
			(at -20.359878 2.789936 180)
			(size 0.450088 0.450088)
			(layers "F.Cu" "F.Mask" "F.Paste")
			(net "Net_2063")
		)
		(pad "BG17" smd circle
			(at -19.420078 2.789936 180)
			(size 0.450088 0.450088)
			(layers "F.Cu" "F.Mask" "F.Paste")
			(net "M_J_CPU1_SB_CA<0>")
		)
		(pad "BG18" smd circle
			(at -18.480024 2.789936 180)
			(size 0.450088 0.450088)
			(layers "F.Cu" "F.Mask" "F.Paste")
			(net "GND")
		)
		(pad "BG19" smd circle
			(at -17.53997 2.789936 180)
			(size 0.450088 0.450088)
			(layers "F.Cu" "F.Mask" "F.Paste")
			(net "Net_2055")
		)
		(pad "BG20" smd circle
			(at -16.599916 2.789936 180)
			(size 0.450088 0.450088)
			(layers "F.Cu" "F.Mask" "F.Paste")
			(net "GND")
		)
		(pad "BG21" smd circle
			(at -15.660116 2.789936 180)
			(size 0.450088 0.450088)
			(layers "F.Cu" "F.Mask" "F.Paste")
			(net "M_I_CPU1_SB_CA<0>")
		)
		(pad "BG22" smd circle
			(at -14.720062 2.789936 180)
			(size 0.450088 0.450088)
			(layers "F.Cu" "F.Mask" "F.Paste")
			(net "PVDDCR_SOC_P1")
		)
		(pad "BG23" smd circle
			(at -13.780008 2.789936 180)
			(size 0.450088 0.450088)
			(layers "F.Cu" "F.Mask" "F.Paste")
			(net "GND")
		)
		(pad "BG24" smd circle
			(at -12.839954 2.789936 180)
			(size 0.450088 0.450088)
			(layers "F.Cu" "F.Mask" "F.Paste")
			(net "PVDDCR_SOC_P1")
		)
		(pad "BG25" smd circle
			(at -11.8999 2.789936 180)
			(size 0.450088 0.450088)
			(layers "F.Cu" "F.Mask" "F.Paste")
			(net "GND")
		)
		(pad "BG26" smd circle
			(at -10.9601 2.789936 180)
			(size 0.450088 0.450088)
			(layers "F.Cu" "F.Mask" "F.Paste")
			(net "PVDDCR_SOC_P1")
		)
		(pad "BG27" smd circle
			(at -10.020046 2.789936 180)
			(size 0.450088 0.450088)
			(layers "F.Cu" "F.Mask" "F.Paste")
			(net "GND")
		)
		(pad "BG28" smd circle
			(at -9.079992 2.789936 180)
			(size 0.450088 0.450088)
			(layers "F.Cu" "F.Mask" "F.Paste")
			(net "PVDDCR_SOC_P1")
		)
		(pad "BG48" smd circle
			(at 8.780018 2.789936 180)
			(size 0.450088 0.450088)
			(layers "F.Cu" "F.Mask" "F.Paste")
			(net "PVDDCR_SOC_P1")
		)
		(pad "BG49" smd circle
			(at 9.720072 2.789936 180)
			(size 0.450088 0.450088)
			(layers "F.Cu" "F.Mask" "F.Paste")
			(net "GND")
		)
		(pad "BG50" smd circle
			(at 10.659872 2.789936 180)
			(size 0.450088 0.450088)
			(layers "F.Cu" "F.Mask" "F.Paste")
			(net "PVDDIO_P1")
		)
		(pad "BG51" smd circle
			(at 11.599926 2.789936 180)
			(size 0.450088 0.450088)
			(layers "F.Cu" "F.Mask" "F.Paste")
			(net "GND")
		)
		(pad "BG52" smd circle
			(at 12.53998 2.789936 180)
			(size 0.450088 0.450088)
			(layers "F.Cu" "F.Mask" "F.Paste")
			(net "PVDDIO_P1")
		)
		(pad "BG53" smd circle
			(at 13.480034 2.789936 180)
			(size 0.450088 0.450088)
			(layers "F.Cu" "F.Mask" "F.Paste")
			(net "GND")
		)
		(pad "BG54" smd circle
			(at 14.420088 2.789936 180)
			(size 0.450088 0.450088)
			(layers "F.Cu" "F.Mask" "F.Paste")
			(net "PVDDIO_P1")
		)
		(pad "BG55" smd circle
			(at 15.359888 2.789936 180)
			(size 0.450088 0.450088)
			(layers "F.Cu" "F.Mask" "F.Paste")
			(net "M_C_CPU1_SB_CA<0>")
		)
		(pad "BG56" smd circle
			(at 16.299942 2.789936 180)
			(size 0.450088 0.450088)
			(layers "F.Cu" "F.Mask" "F.Paste")
			(net "GND")
		)
		(pad "BG57" smd circle
			(at 17.239996 2.789936 180)
			(size 0.450088 0.450088)
			(layers "F.Cu" "F.Mask" "F.Paste")
			(net "Net_2007")
		)
		(pad "BG58" smd circle
			(at 18.18005 2.789936 180)
			(size 0.450088 0.450088)
			(layers "F.Cu" "F.Mask" "F.Paste")
			(net "GND")
		)
		(pad "BG59" smd circle
			(at 19.120104 2.789936 180)
			(size 0.450088 0.450088)
			(layers "F.Cu" "F.Mask" "F.Paste")
			(net "M_D_CPU1_SB_CA<0>")
		)
		(pad "BG60" smd circle
			(at 20.059904 2.789936 180)
			(size 0.450088 0.450088)
			(layers "F.Cu" "F.Mask" "F.Paste")
			(net "Net_2015")
		)
		(pad "BG61" smd circle
			(at 20.999958 2.789936 180)
			(size 0.450088 0.450088)
			(layers "F.Cu" "F.Mask" "F.Paste")
			(net "GND")
		)
		(pad "BG62" smd circle
			(at 21.940012 2.789936 180)
			(size 0.450088 0.450088)
			(layers "F.Cu" "F.Mask" "F.Paste")
			(net "M_B_CPU1_SB_CA<0>")
		)
		(pad "BG63" smd circle
			(at 22.880066 2.789936 180)
			(size 0.450088 0.450088)
			(layers "F.Cu" "F.Mask" "F.Paste")
			(net "GND")
		)
		(pad "BG64" smd circle
			(at 23.82012 2.789936 180)
			(size 0.450088 0.450088)
			(layers "F.Cu" "F.Mask" "F.Paste")
			(net "Net_1999")
		)
		(pad "BG65" smd circle
			(at 24.75992 2.789936 180)
			(size 0.450088 0.450088)
			(layers "F.Cu" "F.Mask" "F.Paste")
			(net "GND")
		)
		(pad "BG66" smd circle
			(at 25.699974 2.789936 180)
			(size 0.450088 0.450088)
			(layers "F.Cu" "F.Mask" "F.Paste")
			(net "M_F_CPU1_SB_CA<0>")
		)
		(pad "BG67" smd circle
			(at 26.640028 2.789936 180)
			(size 0.450088 0.450088)
			(layers "F.Cu" "F.Mask" "F.Paste")
			(net "Net_2031")
		)
		(pad "BG68" smd circle
			(at 27.580082 2.789936 180)
			(size 0.450088 0.450088)
			(layers "F.Cu" "F.Mask" "F.Paste")
			(net "GND")
		)
		(pad "BG69" smd circle
			(at 28.519882 2.789936 180)
			(size 0.450088 0.450088)
			(layers "F.Cu" "F.Mask" "F.Paste")
			(net "M_E_CPU1_SB_CA<0>")
		)
		(pad "BG70" smd circle
			(at 29.459936 2.789936 180)
			(size 0.450088 0.450088)
			(layers "F.Cu" "F.Mask" "F.Paste")
			(net "GND")
		)
		(pad "BG71" smd circle
			(at 30.39999 2.789936 180)
			(size 0.450088 0.450088)
			(layers "F.Cu" "F.Mask" "F.Paste")
			(net "Net_2023")
		)
		(pad "BG72" smd circle
			(at 31.340044 2.789936 180)
			(size 0.450088 0.450088)
			(layers "F.Cu" "F.Mask" "F.Paste")
			(net "GND")
		)
		(pad "BG73" smd circle
			(at 32.280098 2.789936 180)
			(size 0.450088 0.450088)
			(layers "F.Cu" "F.Mask" "F.Paste")
			(net "M_A_CPU1_SB_CA<0>")
		)
		(pad "BG74" smd circle
			(at 33.219898 2.789936 180)
			(size 0.450088 0.450088)
			(layers "F.Cu" "F.Mask" "F.Paste")
			(net "Net_1991")
		)
		(pad "BG75" smd circle
			(at 34.159952 2.789936 180)
			(size 0.450088 0.450088)
			(layers "F.Cu" "F.Mask" "F.Paste")
			(net "GND")
		)
		(pad "BH2" smd circle
			(at -33.990026 3.599942 180)
			(size 0.450088 0.450088)
			(layers "F.Cu" "F.Mask" "F.Paste")
			(net "M_G_CPU1_SB_CA<2>")
		)
		(pad "BH3" smd circle
			(at -33.049972 3.599942 180)
			(size 0.450088 0.450088)
			(layers "F.Cu" "F.Mask" "F.Paste")
			(net "GND")
		)
		(pad "BH4" smd circle
			(at -32.109918 3.599942 180)
			(size 0.450088 0.450088)
			(layers "F.Cu" "F.Mask" "F.Paste")
			(net "M_G_CPU1_SB_CA<1>")
		)
		(pad "BH5" smd circle
			(at -31.170118 3.599942 180)
			(size 0.450088 0.450088)
			(layers "F.Cu" "F.Mask" "F.Paste")
			(net "GND")
		)
		(pad "BH6" smd circle
			(at -30.230064 3.599942 180)
			(size 0.450088 0.450088)
			(layers "F.Cu" "F.Mask" "F.Paste")
			(net "M_K_CPU1_SB_CA<2>")
		)
		(pad "BH7" smd circle
			(at -29.29001 3.599942 180)
			(size 0.450088 0.450088)
			(layers "F.Cu" "F.Mask" "F.Paste")
			(net "M_K_CPU1_SB_CA<1>")
		)
		(pad "BH8" smd circle
			(at -28.349956 3.599942 180)
			(size 0.450088 0.450088)
			(layers "F.Cu" "F.Mask" "F.Paste")
			(net "GND")
		)
		(pad "BH9" smd circle
			(at -27.409902 3.599942 180)
			(size 0.450088 0.450088)
			(layers "F.Cu" "F.Mask" "F.Paste")
			(net "M_L_CPU1_SB_CA<2>")
		)
		(pad "BH10" smd circle
			(at -26.470102 3.599942 180)
			(size 0.450088 0.450088)
			(layers "F.Cu" "F.Mask" "F.Paste")
			(net "GND")
		)
	)
)
